# T6G (Grand Teton) — schematic netlist excerpt (pin names and nets, part order shuffled) for the footprints in the layout excerpt that follows; sources: Cadence DE-HDL packaged netlist, KiCad conversion of 04192023_DAF0TMB3IC0_F0TG_MB_C_brd_V02_OCP.brd

R9014  Q_RES  10K 1% CHIP  pkg 0402LF  page 123 : A = P3V3_AUX ; B = PRSNT_CABLE_GPU_A3_N
C872  Q_CAP_DIFFBUS  DIFF BUS_0.22UF 6.3V 20% X6S  pkg C0201  page 64 : \1\ = P5E_CPU0_P3_TX_C_DN<14> ; \2\ = P5E_CPU0_P3_TX_DN<14>
R1322  Q_RES  4.7K 1% CHIP  pkg 0402LF  page 357 : A = P3V3_AUX ; B = INA230_7_A1

(kicad_pcb
	(version 20260206)
	(generator "pcbnew")
	(generator_version "10.0")
	(general
		(thickness 1.6)
		(legacy_teardrops no)
	)
	(paper "A4")
	(title_block
		(title "04192023_DAF0TMB3IC0_F0TG_MB_C_brd_V02_OCP.brd")
		(comment 1 "Grand Teton / footprints 853-855 of 8354")
	)
	(layers
		(0 "F.Cu" signal "TOP")
		(4 "In1.Cu" signal "GND")
		(6 "In2.Cu" signal "IN1")
		(8 "In3.Cu" signal "GND1")
		(10 "In4.Cu" signal "IN2")
		(12 "In5.Cu" signal "GND2")
		(14 "In6.Cu" signal "IN3")
		(16 "In7.Cu" signal "GND3")
		(18 "In8.Cu" signal "VCC")
		(20 "In9.Cu" signal "VCC1")
		(22 "In10.Cu" signal "GND4")
		(24 "In11.Cu" signal "IN4")
		(26 "In12.Cu" signal "GND5")
		(28 "In13.Cu" signal "IN5")
		(30 "In14.Cu" signal "GND6")
		(32 "In15.Cu" signal "IN6")
		(34 "In16.Cu" signal "GND7")
		(2 "B.Cu" signal "BOTTOM")
		(9 "F.Adhes" user "F.Adhesive")
		(11 "B.Adhes" user "B.Adhesive")
		(13 "F.Paste" user "Package Geometry/Pastemask Top")
		(15 "B.Paste" user "Package Geometry/Pastemask Bottom")
		(5 "F.SilkS" user "Ref Des/Silkscreen Top")
		(7 "B.SilkS" user "Ref Des/Silkscreen Bottom")
		(1 "F.Mask" user "Board Geometry/Soldermask Top")
		(3 "B.Mask" user "Board Geometry/Soldermask Bottom")
		(17 "Dwgs.User" user "User.Drawings")
		(19 "Cmts.User" user "User.Comments")
		(21 "Eco1.User" user "User.Eco1")
		(23 "Eco2.User" user "User.Eco2")
		(25 "Edge.Cuts" user "Board Geometry/Outline")
		(27 "Margin" user)
		(31 "F.CrtYd" user "Package Geometry/Place Bound Top")
		(29 "B.CrtYd" user "Package Geometry/Place Bound Bottom")
		(35 "F.Fab" user "Ref Des/Assembly Top")
		(33 "B.Fab" user "Ref Des/Assembly Bottom")
	)
	(footprint ""
		(layer "F.Cu")
		(at 362.025438 -409.947364)
		(property "Reference" "R9014"
			(at 0 0 0)
			(layer "F.SilkS")
			(hide yes)
			(effects
				(font
					(size 1.27 1.27)
				)
			)
		)
		(property "Value" ""
			(at 0 0 0)
			(layer "F.Fab")
			(effects
				(font
					(size 1.27 1.27)
				)
			)
		)
		(duplicate_pad_numbers_are_jumpers no)
		(fp_line
			(start -0.7874 -0.4064)
			(end 0.7874 -0.4064)
			(stroke
				(width 0.1524)
				(type default)
			)
			(layer "F.SilkS")
		)
		(fp_line
			(start -0.7874 0.4064)
			(end -0.7874 -0.4064)
			(stroke
				(width 0.1524)
				(type default)
			)
			(layer "F.SilkS")
		)
		(fp_line
			(start 0.7874 -0.4064)
			(end 0.7874 0.4064)
			(stroke
				(width 0.1524)
				(type default)
			)
			(layer "F.SilkS")
		)
		(fp_line
			(start 0.7874 0.4064)
			(end -0.7874 0.4064)
			(stroke
				(width 0.1524)
				(type default)
			)
			(layer "F.SilkS")
		)
		(fp_line
			(start -0.67945 -0.305054)
			(end -0.12065 -0.305054)
			(stroke
				(width 0.1)
				(type default)
			)
			(layer "F.Fab")
		)
		(fp_line
			(start -0.67945 0.3048)
			(end -0.67945 -0.305054)
			(stroke
				(width 0.1)
				(type default)
			)
			(layer "F.Fab")
		)
		(fp_line
			(start -0.12065 -0.305054)
			(end -0.12065 -0.2794)
			(stroke
				(width 0.1)
				(type default)
			)
			(layer "F.Fab")
		)
		(fp_line
			(start -0.12065 -0.2794)
			(end 0.12065 -0.2794)
			(stroke
				(width 0.1)
				(type default)
			)
			(layer "F.Fab")
		)
		(fp_line
			(start -0.12065 0.2794)
			(end -0.12065 0.3048)
			(stroke
				(width 0.1)
				(type default)
			)
			(layer "F.Fab")
		)
		(fp_line
			(start -0.12065 0.3048)
			(end -0.67945 0.3048)
			(stroke
				(width 0.1)
				(type default)
			)
			(layer "F.Fab")
		)
		(fp_line
			(start 0.120396 0.2794)
			(end -0.12065 0.2794)
			(stroke
				(width 0.1)
				(type default)
			)
			(layer "F.Fab")
		)
		(fp_line
			(start 0.120396 0.3048)
			(end 0.120396 0.2794)
			(stroke
				(width 0.1)
				(type default)
			)
			(layer "F.Fab")
		)
		(fp_line
			(start 0.12065 -0.3048)
			(end 0.67945 -0.3048)
			(stroke
				(width 0.1)
				(type default)
			)
			(layer "F.Fab")
		)
		(fp_line
			(start 0.12065 -0.2794)
			(end 0.12065 -0.3048)
			(stroke
				(width 0.1)
				(type default)
			)
			(layer "F.Fab")
		)
		(fp_line
			(start 0.67945 -0.3048)
			(end 0.67945 0.3048)
			(stroke
				(width 0.1)
				(type default)
			)
			(layer "F.Fab")
		)
		(fp_line
			(start 0.67945 0.3048)
			(end 0.120396 0.3048)
			(stroke
				(width 0.1)
				(type default)
			)
			(layer "F.Fab")
		)
		(pad "1" smd circle
			(at -0.40005 0)
			(size 0 0)
			(layers "F.Cu" "F.Mask" "F.Paste")
			(net "P3V3_AUX")
		)
		(pad "2" smd circle
			(at 0.40005 0)
			(size 0 0)
			(layers "F.Cu" "F.Mask" "F.Paste")
			(net "PRSNT_CABLE_GPU_A3_N")
		)
	)
	(footprint ""
		(layer "F.Cu")
		(at 392.840972 -384.449828)
		(property "Reference" "C872"
			(at 0 0 0)
			(layer "F.SilkS")
			(hide yes)
			(effects
				(font
					(size 1.27 1.27)
				)
			)
		)
		(property "Value" ""
			(at 0 0 0)
			(layer "F.Fab")
			(effects
				(font
					(size 1.27 1.27)
				)
			)
		)
		(duplicate_pad_numbers_are_jumpers no)
		(fp_line
			(start -0.299974 -0.150114)
			(end 0.299974 -0.150114)
			(stroke
				(width 0.1)
				(type default)
			)
			(layer "F.Fab")
		)
		(fp_line
			(start -0.299974 0.150114)
			(end -0.299974 -0.150114)
			(stroke
				(width 0.1)
				(type default)
			)
			(layer "F.Fab")
		)
		(fp_line
			(start 0.299974 -0.150114)
			(end 0.299974 0.150114)
			(stroke
				(width 0.1)
				(type default)
			)
			(layer "F.Fab")
		)
		(fp_line
			(start 0.299974 0.150114)
			(end -0.299974 0.150114)
			(stroke
				(width 0.1)
				(type default)
			)
			(layer "F.Fab")
		)
		(pad "1" smd rect
			(at -0.2667 0)
			(size 0.3048 0.381)
			(layers "F.Cu" "F.Mask" "F.Paste")
			(net "P5E_CPU0_P3_TX_C_DN<14>")
		)
		(pad "2" smd rect
			(at 0.2667 0)
			(size 0.3048 0.381)
			(layers "F.Cu" "F.Mask" "F.Paste")
			(net "P5E_CPU0_P3_TX_DN<14>")
		)
	)
	(footprint ""
		(layer "F.Cu")
		(at 19.241516 -41.958514)
		(property "Reference" "R1322"
			(at 0 0 0)
			(layer "F.SilkS")
			(hide yes)
			(effects
				(font
					(size 1.27 1.27)
				)
			)
		)
		(property "Value" ""
			(at 0 0 0)
			(layer "F.Fab")
			(effects
				(font
					(size 1.27 1.27)
				)
			)
		)
		(duplicate_pad_numbers_are_jumpers no)
		(fp_line
			(start -0.7874 -0.4064)
			(end 0.7874 -0.4064)
			(stroke
				(width 0.1524)
				(type default)
			)
			(layer "F.SilkS")
		)
		(fp_line
			(start -0.7874 0.4064)
			(end -0.7874 -0.4064)
			(stroke
				(width 0.1524)
				(type default)
			)
			(layer "F.SilkS")
		)
		(fp_line
			(start 0.7874 -0.4064)
			(end 0.7874 0.4064)
			(stroke
				(width 0.1524)
				(type default)
			)
			(layer "F.SilkS")
		)
		(fp_line
			(start 0.7874 0.4064)
			(end -0.7874 0.4064)
			(stroke
				(width 0.1524)
				(type default)
			)
			(layer "F.SilkS")
		)
		(fp_line
			(start -0.67945 -0.305054)
			(end -0.12065 -0.305054)
			(stroke
				(width 0.1)
				(type default)
			)
			(layer "F.Fab")
		)
		(fp_line
			(start -0.67945 0.3048)
			(end -0.67945 -0.305054)
			(stroke
				(width 0.1)
				(type default)
			)
			(layer "F.Fab")
		)
		(fp_line
			(start -0.12065 -0.305054)
			(end -0.12065 -0.2794)
			(stroke
				(width 0.1)
				(type default)
			)
			(layer "F.Fab")
		)
		(fp_line
			(start -0.12065 -0.2794)
			(end 0.12065 -0.2794)
			(stroke
				(width 0.1)
				(type default)
			)
			(layer "F.Fab")
		)
		(fp_line
			(start -0.12065 0.2794)
			(end -0.12065 0.3048)
			(stroke
				(width 0.1)
				(type default)
			)
			(layer "F.Fab")
		)
		(fp_line
			(start -0.12065 0.3048)
			(end -0.67945 0.3048)
			(stroke
				(width 0.1)
				(type default)
			)
			(layer "F.Fab")
		)
		(fp_line
			(start 0.120396 0.2794)
			(end -0.12065 0.2794)
			(stroke
				(width 0.1)
				(type default)
			)
			(layer "F.Fab")
		)
		(fp_line
			(start 0.120396 0.3048)
			(end 0.120396 0.2794)
			(stroke
				(width 0.1)
				(type default)
			)
			(layer "F.Fab")
		)
		(fp_line
			(start 0.12065 -0.3048)
			(end 0.67945 -0.3048)
			(stroke
				(width 0.1)
				(type default)
			)
			(layer "F.Fab")
		)
		(fp_line
			(start 0.12065 -0.2794)
			(end 0.12065 -0.3048)
			(stroke
				(width 0.1)
				(type default)
			)
			(layer "F.Fab")
		)
		(fp_line
			(start 0.67945 -0.3048)
			(end 0.67945 0.3048)
			(stroke
				(width 0.1)
				(type default)
			)
			(layer "F.Fab")
		)
		(fp_line
			(start 0.67945 0.3048)
			(end 0.120396 0.3048)
			(stroke
				(width 0.1)
				(type default)
			)
			(layer "F.Fab")
		)
		(pad "1" smd circle
			(at -0.40005 0)
			(size 0 0)
			(layers "F.Cu" "F.Mask" "F.Paste")
			(net "P3V3_AUX")
		)
		(pad "2" smd circle
			(at 0.40005 0)
			(size 0 0)
			(layers "F.Cu" "F.Mask" "F.Paste")
			(net "INA230_7_A1")
		)
	)
)
